(kicad_pcb
	(version 20241229)
	(generator "pcbnew")
	(generator_version "9.0")
	(general
		(thickness 1.552)
		(legacy_teardrops no)
	)
	(paper "A4")
	(title_block
		(date "2023-07-25")
		(rev "1.1.4")
		(comment 9 "footprints 90-94 of 379")
	)
	(layers
		(0 "F.Cu" signal)
		(4 "In1.Cu" signal)
		(6 "In2.Cu" signal)
		(8 "In3.Cu" signal)
		(10 "In4.Cu" signal)
		(12 "In5.Cu" signal)
		(14 "In6.Cu" signal)
		(2 "B.Cu" signal)
		(9 "F.Adhes" user "F.Adhesive")
		(11 "B.Adhes" user "B.Adhesive")
		(13 "F.Paste" user)
		(15 "B.Paste" user)
		(5 "F.SilkS" user "F.Silkscreen")
		(7 "B.SilkS" user "B.Silkscreen")
		(1 "F.Mask" user)
		(3 "B.Mask" user)
		(17 "Dwgs.User" user "User.Drawings")
		(19 "Cmts.User" user "User.Comments")
		(21 "Eco1.User" user "User.Eco1")
		(23 "Eco2.User" user "User.Eco2")
		(25 "Edge.Cuts" user)
		(27 "Margin" user)
		(31 "F.CrtYd" user "F.Courtyard")
		(29 "B.CrtYd" user "B.Courtyard")
		(35 "F.Fab" user)
		(33 "B.Fab" user)
	)
	(footprint "antmicro-footprints:PinHeader_2x5_P1.27mm_SMD"
		(layer "F.Cu")
		(at 89 119.7 180)
		(property "Reference" "J5"
			(at 3.67 2.26 0)
			(layer "F.SilkS")
			(effects
				(font
					(size 0.65 0.65)
					(thickness 0.15)
				)
				(justify right bottom)
			)
		)
		(property "Value" "PinHeader_2x5_P1.27mm_SMD"
			(at 0 4.2 0)
			(layer "F.Fab")
			(hide yes)
			(effects
				(font
					(size 0.7 0.7)
					(thickness 0.15)
				)
				(justify right bottom)
			)
		)
		(property "Datasheet" "https://eu.mouser.com/datasheet/2/527/ftsh_th-2854322.pdf"
			(at 0 0 180)
			(layer "F.Fab")
			(hide yes)
			(effects
				(font
					(size 1.27 1.27)
					(thickness 0.15)
				)
			)
		)
		(property "Description" "Pin Header, Board-to-Board, Wire-to-Board, 1.27 mm, 2 Rows, 10 Contacts, Surface Mount, FTSH"
			(at 0 0 180)
			(layer "F.Fab")
			(hide yes)
			(effects
				(font
					(size 1.27 1.27)
					(thickness 0.15)
				)
			)
		)
		(property "Author" "Antmicro"
			(at 178 239.4 0)
			(layer "F.Fab")
			(hide yes)
			(effects
				(font
					(size 1 1)
					(thickness 0.15)
				)
			)
		)
		(property "License" "Apache-2.0"
			(at 178 239.4 0)
			(layer "F.Fab")
			(hide yes)
			(effects
				(font
					(size 1 1)
					(thickness 0.15)
				)
			)
		)
		(property "MPN" "FTSH-105-01-F-DV"
			(at 178 239.4 0)
			(layer "F.Fab")
			(hide yes)
			(effects
				(font
					(size 1 1)
					(thickness 0.15)
				)
			)
		)
		(property "Manufacturer" "Samtec"
			(at 178 239.4 0)
			(layer "F.Fab")
			(hide yes)
			(effects
				(font
					(size 1 1)
					(thickness 0.15)
				)
			)
		)
		(sheetname "/Peripherals/")
		(sheetfile "peripherals.kicad_sch")
		(attr smd)
		(fp_line
			(start 3.257 1.8)
			(end 3.257 1.499)
			(stroke
				(width 0.15)
				(type solid)
			)
			(layer "F.SilkS")
		)
		(fp_line
			(start 3.257 -1.801)
			(end 3.257 -1.5)
			(stroke
				(width 0.15)
				(type solid)
			)
			(layer "F.SilkS")
		)
		(fp_line
			(start 2.959 1.8)
			(end 3.257 1.8)
			(stroke
				(width 0.15)
				(type solid)
			)
			(layer "F.SilkS")
		)
		(fp_line
			(start 2.959 -1.801)
			(end 3.257 -1.801)
			(stroke
				(width 0.15)
				(type solid)
			)
			(layer "F.SilkS")
		)
		(fp_line
			(start -3.04 1.8)
			(end -3.34 1.8)
			(stroke
				(width 0.15)
				(type solid)
			)
			(layer "F.SilkS")
		)
		(fp_line
			(start -3.04 -1.801)
			(end -3.34 -1.801)
			(stroke
				(width 0.15)
				(type solid)
			)
			(layer "F.SilkS")
		)
		(fp_line
			(start -3.34 1.8)
			(end -3.34 1.499)
			(stroke
				(width 0.15)
				(type solid)
			)
			(layer "F.SilkS")
		)
		(fp_line
			(start -3.34 -1.801)
			(end -3.34 -1.5)
			(stroke
				(width 0.15)
				(type solid)
			)
			(layer "F.SilkS")
		)
		(fp_rect
			(start -3.476 -3.25)
			(end 3.373 3.249)
			(stroke
				(width 0.05)
				(type solid)
			)
			(fill no)
			(layer "F.CrtYd")
		)
		(fp_line
			(start 3.132 1.715)
			(end -3.215 1.715)
			(stroke
				(width 0.15)
				(type solid)
			)
			(layer "F.Fab")
		)
		(fp_line
			(start 3.132 -1.716)
			(end 3.132 1.715)
			(stroke
				(width 0.15)
				(type solid)
			)
			(layer "F.Fab")
		)
		(fp_line
			(start 3.132 -1.716)
			(end -3.215 -1.716)
			(stroke
				(width 0.15)
				(type solid)
			)
			(layer "F.Fab")
		)
		(fp_line
			(start -3.215 -1.716)
			(end -3.215 1.715)
			(stroke
				(width 0.15)
				(type solid)
			)
			(layer "F.Fab")
		)
		(pad "1" smd rect
			(at -2.581 1.949 180)
			(size 0.76 2.4)
			(layers "F.Cu" "F.Mask" "F.Paste")
			(net 20 "AUDIO_ACLK")
			(pintype "passive")
		)
		(pad "2" smd rect
			(at -2.581 -1.95 180)
			(size 0.76 2.4)
			(layers "F.Cu" "F.Mask" "F.Paste")
			(net 20 "AUDIO_ACLK")
			(pintype "passive")
		)
		(pad "3" smd rect
			(at -1.311 1.949 180)
			(size 0.76 2.4)
			(layers "F.Cu" "F.Mask" "F.Paste")
			(net 21 "AUDIO_WCLK")
			(pintype "passive")
		)
		(pad "4" smd rect
			(at -1.311 -1.95 180)
			(size 0.76 2.4)
			(layers "F.Cu" "F.Mask" "F.Paste")
			(net 21 "AUDIO_WCLK")
			(pintype "passive")
		)
		(pad "5" smd rect
			(at -0.042 1.949 180)
			(size 0.76 2.4)
			(layers "F.Cu" "F.Mask" "F.Paste")
			(net 22 "AUDIO_OUT_CH1_2")
			(pintype "passive")
		)
		(pad "6" smd rect
			(at -0.042 -1.95 180)
			(size 0.76 2.4)
			(layers "F.Cu" "F.Mask" "F.Paste")
			(net 23 "AUDIO_OUT_CH5_6")
			(pintype "passive")
		)
		(pad "7" smd rect
			(at 1.227 1.949 180)
			(size 0.76 2.4)
			(layers "F.Cu" "F.Mask" "F.Paste")
			(net 24 "AUDIO_OUT_CH3_4")
			(pintype "passive")
		)
		(pad "8" smd rect
			(at 1.227 -1.95 180)
			(size 0.76 2.4)
			(layers "F.Cu" "F.Mask" "F.Paste")
			(net 25 "AUDIO_OUT_CH7_8")
			(pintype "passive")
		)
		(pad "9" smd rect
			(at 2.499 1.949 180)
			(size 0.76 2.4)
			(layers "F.Cu" "F.Mask" "F.Paste")
			(net 1 "GND")
			(pintype "passive")
		)
		(pad "10" smd rect
			(at 2.499 -1.95 180)
			(size 0.76 2.4)
			(layers "F.Cu" "F.Mask" "F.Paste")
			(net 26 "AUDIO_MCLK")
			(pintype "passive")
		)
	)
	(footprint "antmicro-footprints:C_0603_1608Metric"
		(layer "F.Cu")
		(at 144.39 63.89 180)
		(descr "Capacitor SMD 0603")
		(tags "capacitor 0603")
		(property "Reference" "C21"
			(at 5.36 -0.45 0)
			(layer "F.SilkS")
			(effects
				(font
					(size 0.65 0.65)
					(thickness 0.15)
				)
				(justify right bottom)
			)
		)
		(property "Value" "C_22u_0603"
			(at 0 1.6 0)
			(layer "F.Fab")
			(hide yes)
			(effects
				(font
					(size 0.7 0.7)
					(thickness 0.15)
				)
				(justify right bottom)
			)
		)
		(property "Datasheet" "https://www.murata.com/products/productdetail?partno=GRM188R60J226MEA0%23"
			(at 0 0 180)
			(layer "F.Fab")
			(hide yes)
			(effects
				(font
					(size 1.27 1.27)
					(thickness 0.15)
				)
			)
		)
		(property "Description" "SMD Multilayer Ceramic Capacitor, 22 µF, 6.3 V, 0603 [1608 Metric], ± 20%, X5R, GRM Series"
			(at 0 0 180)
			(layer "F.Fab")
			(hide yes)
			(effects
				(font
					(size 1.27 1.27)
					(thickness 0.15)
				)
			)
		)
		(property "Author" "Antmicro"
			(at 288.78 127.78 0)
			(layer "F.Fab")
			(hide yes)
			(effects
				(font
					(size 1 1)
					(thickness 0.15)
				)
			)
		)
		(property "Dielectric" ""
			(at 288.78 127.78 0)
			(layer "F.Fab")
			(hide yes)
			(effects
				(font
					(size 1 1)
					(thickness 0.15)
				)
			)
		)
		(property "License" "Apache-2.0"
			(at 288.78 127.78 0)
			(layer "F.Fab")
			(hide yes)
			(effects
				(font
					(size 1 1)
					(thickness 0.15)
				)
			)
		)
		(property "MPN" "GRM188R60J226MEA0D"
			(at 288.78 127.78 0)
			(layer "F.Fab")
			(hide yes)
			(effects
				(font
					(size 1 1)
					(thickness 0.15)
				)
			)
		)
		(property "Manufacturer" "Murata"
			(at 288.78 127.78 0)
			(layer "F.Fab")
			(hide yes)
			(effects
				(font
					(size 1 1)
					(thickness 0.15)
				)
			)
		)
		(property "Val" "22u"
			(at 288.78 127.78 0)
			(layer "F.Fab")
			(hide yes)
			(effects
				(font
					(size 1 1)
					(thickness 0.15)
				)
			)
		)
		(property "Voltage" ""
			(at 288.78 127.78 0)
			(layer "F.Fab")
			(hide yes)
			(effects
				(font
					(size 1 1)
					(thickness 0.15)
				)
			)
		)
		(sheetname "/Power Supply/")
		(sheetfile "supply.kicad_sch")
		(attr smd)
		(fp_line
			(start -0.15 0.4)
			(end 0.15 0.4)
			(stroke
				(width 0.15)
				(type solid)
			)
			(layer "F.SilkS")
		)
		(fp_line
			(start -0.15 -0.4)
			(end 0.15 -0.4)
			(stroke
				(width 0.15)
				(type solid)
			)
			(layer "F.SilkS")
		)
		(fp_rect
			(start -1.25 -0.65)
			(end 1.25 0.65)
			(stroke
				(width 0.05)
				(type solid)
			)
			(fill no)
			(layer "F.CrtYd")
		)
		(fp_rect
			(start -0.8 -0.4)
			(end 0.8 0.4)
			(stroke
				(width 0.15)
				(type solid)
			)
			(fill no)
			(layer "F.Fab")
		)
		(fp_text user "License: Apache-2.0"
			(at -1.682 5.895 180)
			(layer "F.Fab")
			(effects
				(font
					(size 0.7 0.7)
					(thickness 0.15)
				)
				(justify left bottom)
			)
		)
		(fp_text user "Author: Antmicro"
			(at -1.682 4.894 180)
			(layer "F.Fab")
			(effects
				(font
					(size 0.7 0.7)
					(thickness 0.15)
				)
				(justify left bottom)
			)
		)
		(fp_text user "${REFERENCE}"
			(at -1.682 3.895 180)
			(layer "F.Fab")
			(effects
				(font
					(size 0.7 0.7)
					(thickness 0.15)
				)
				(justify left bottom)
			)
		)
		(pad "1" smd roundrect
			(at -0.7 0 180)
			(size 0.8 1)
			(layers "F.Cu" "F.Mask" "F.Paste")
			(roundrect_rratio 0.2)
			(net 1 "GND")
			(pintype "passive")
		)
		(pad "2" smd roundrect
			(at 0.7 0 180)
			(size 0.8 1)
			(layers "F.Cu" "F.Mask" "F.Paste")
			(roundrect_rratio 0.2)
			(net 274 "/Power Supply/1V5_OUT")
			(pintype "passive")
		)
	)
	(footprint "antmicro-footprints:R_0402_1005Metric"
		(layer "F.Cu")
		(at 92.6 104.85)
		(descr "Resistor SMD 0402")
		(tags "resistor SMD 0402")
		(property "Reference" "R57"
			(at 0.93 0.39 0)
			(layer "F.SilkS")
			(effects
				(font
					(size 0.65 0.65)
					(thickness 0.15)
				)
				(justify left bottom)
			)
		)
		(property "Value" "R_750R_0402"
			(at 0 1.4 0)
			(layer "F.Fab")
			(hide yes)
			(effects
				(font
					(size 0.7 0.7)
					(thickness 0.15)
				)
				(justify left bottom)
			)
		)
		(property "Datasheet" "https://www.bourns.com/docs/product-datasheets/cr.pdf"
			(at 0 0 0)
			(layer "F.Fab")
			(hide yes)
			(effects
				(font
					(size 1.27 1.27)
					(thickness 0.15)
				)
			)
		)
		(property "Description" "SMD Chip Resistor, 750 ohm, ± 1%, 63 mW, 0402 [1005 Metric], Thick Film, General Purpose"
			(at 0 0 0)
			(layer "F.Fab")
			(hide yes)
			(effects
				(font
					(size 1.27 1.27)
					(thickness 0.15)
				)
			)
		)
		(property "Author" "Antmicro"
			(at 0 0 0)
			(layer "F.Fab")
			(hide yes)
			(effects
				(font
					(size 1 1)
					(thickness 0.15)
				)
			)
		)
		(property "License" "Apache-2.0"
			(at 0 0 0)
			(layer "F.Fab")
			(hide yes)
			(effects
				(font
					(size 1 1)
					(thickness 0.15)
				)
			)
		)
		(property "MPN" "CR0402-FX-7500GLF"
			(at 0 0 0)
			(layer "F.Fab")
			(hide yes)
			(effects
				(font
					(size 1 1)
					(thickness 0.15)
				)
			)
		)
		(property "Manufacturer" "Bourns"
			(at 0 0 0)
			(layer "F.Fab")
			(hide yes)
			(effects
				(font
					(size 1 1)
					(thickness 0.15)
				)
			)
		)
		(property "Tolerance" "1%"
			(at 0 0 0)
			(layer "F.Fab")
			(hide yes)
			(effects
				(font
					(size 1 1)
					(thickness 0.15)
				)
			)
		)
		(property "Val" "750R"
			(at 0 0 0)
			(layer "F.Fab")
			(hide yes)
			(effects
				(font
					(size 1 1)
					(thickness 0.15)
				)
			)
		)
		(sheetname "/SDI/")
		(sheetfile "sdi.kicad_sch")
		(attr smd)
		(fp_rect
			(start -0.925 -0.47)
			(end 0.925 0.47)
			(stroke
				(width 0.05)
				(type default)
			)
			(fill no)
			(layer "F.CrtYd")
		)
		(fp_rect
			(start -0.5 -0.25)
			(end 0.5 0.25)
			(stroke
				(width 0.15)
				(type solid)
			)
			(fill no)
			(layer "F.Fab")
		)
		(fp_text user "${REFERENCE}"
			(at -0.95 3.168 0)
			(layer "F.Fab")
			(effects
				(font
					(size 0.7 0.7)
					(thickness 0.15)
				)
				(justify left bottom)
			)
		)
		(fp_text user "Author: Antmicro"
			(at -0.95 4.169 0)
			(layer "F.Fab")
			(effects
				(font
					(size 0.7 0.7)
					(thickness 0.15)
				)
				(justify left bottom)
			)
		)
		(fp_text user "License: Apache-2.0"
			(at -0.95 5.169 0)
			(layer "F.Fab")
			(effects
				(font
					(size 0.7 0.7)
					(thickness 0.15)
				)
				(justify left bottom)
			)
		)
		(pad "1" smd roundrect
			(at -0.48 0)
			(size 0.59 0.64)
			(layers "F.Cu" "F.Mask" "F.Paste")
			(roundrect_rratio 0.25)
			(net 289 "Net-(U16-RSET)")
			(pintype "passive")
		)
		(pad "2" smd roundrect
			(at 0.48 0)
			(size 0.59 0.64)
			(layers "F.Cu" "F.Mask" "F.Paste")
			(roundrect_rratio 0.25)
			(net 2 "+3V3")
			(pintype "passive")
		)
	)
	(footprint "antmicro-footprints:C_0402_1005Metric"
		(layer "F.Cu")
		(at 95.71 89.21 180)
		(descr "Capacitor SMD 0402")
		(tags "capacitor SMD 0402")
		(property "Reference" "C52"
			(at 1.08 -1.4 180)
			(layer "F.SilkS")
			(effects
				(font
					(size 0.65 0.65)
					(thickness 0.15)
				)
				(justify left bottom)
			)
		)
		(property "Value" "C_33p_0402"
			(at 0 1.4 180)
			(layer "F.Fab")
			(hide yes)
			(effects
				(font
					(size 0.7 0.7)
					(thickness 0.15)
				)
				(justify left bottom)
			)
		)
		(property "Datasheet" "https://spicat.kyocera-avx.com/product/mlcc/chartview/04025A330FAT2A/"
			(at 0 0 180)
			(layer "F.Fab")
			(hide yes)
			(effects
				(font
					(size 1.27 1.27)
					(thickness 0.15)
				)
			)
		)
		(property "Description" "SMD Multilayer Ceramic Capacitor, 33 pF, 50 V, 0402 [1005 Metric], ± 5%, C0G / NP0, MC"
			(at 0 0 180)
			(layer "F.Fab")
			(hide yes)
			(effects
				(font
					(size 1.27 1.27)
					(thickness 0.15)
				)
			)
		)
		(property "Author" "Antmicro"
			(at 191.42 178.28 0)
			(layer "F.Fab")
			(hide yes)
			(effects
				(font
					(size 1 1)
					(thickness 0.15)
				)
			)
		)
		(property "Dielectric" ""
			(at 191.42 178.28 0)
			(layer "F.Fab")
			(hide yes)
			(effects
				(font
					(size 1 1)
					(thickness 0.15)
				)
			)
		)
		(property "License" "Apache-2.0"
			(at 191.42 178.28 0)
			(layer "F.Fab")
			(hide yes)
			(effects
				(font
					(size 1 1)
					(thickness 0.15)
				)
			)
		)
		(property "MPN" "04025A330FAT2A"
			(at 191.42 178.28 0)
			(layer "F.Fab")
			(hide yes)
			(effects
				(font
					(size 1 1)
					(thickness 0.15)
				)
			)
		)
		(property "Manufacturer" "KYOCERA AVX"
			(at 191.42 178.28 0)
			(layer "F.Fab")
			(hide yes)
			(effects
				(font
					(size 1 1)
					(thickness 0.15)
				)
			)
		)
		(property "Val" "33p"
			(at 191.42 178.28 0)
			(layer "F.Fab")
			(hide yes)
			(effects
				(font
					(size 1 1)
					(thickness 0.15)
				)
			)
		)
		(property "Voltage" ""
			(at 191.42 178.28 0)
			(layer "F.Fab")
			(hide yes)
			(effects
				(font
					(size 1 1)
					(thickness 0.15)
				)
			)
		)
		(sheetname "/SDI/")
		(sheetfile "sdi.kicad_sch")
		(attr smd)
		(fp_rect
			(start -0.925 -0.47)
			(end 0.925 0.47)
			(stroke
				(width 0.05)
				(type default)
			)
			(fill no)
			(layer "F.CrtYd")
		)
		(fp_line
			(start 0.504 0.248)
			(end -0.494 0.248)
			(stroke
				(width 0.15)
				(type solid)
			)
			(layer "F.Fab")
		)
		(fp_line
			(start 0.504 -0.25)
			(end 0.504 0.248)
			(stroke
				(width 0.15)
				(type solid)
			)
			(layer "F.Fab")
		)
		(fp_line
			(start -0.494 0.248)
			(end -0.494 -0.25)
			(stroke
				(width 0.15)
				(type solid)
			)
			(layer "F.Fab")
		)
		(fp_line
			(start -0.494 -0.25)
			(end 0.504 -0.25)
			(stroke
				(width 0.15)
				(type solid)
			)
			(layer "F.Fab")
		)
		(fp_text user "Author: Antmicro"
			(at -0.939 3.399 180)
			(layer "F.Fab")
			(effects
				(font
					(size 0.7 0.7)
					(thickness 0.15)
				)
				(justify left bottom)
			)
		)
		(fp_text user "${REFERENCE}"
			(at -0.939 4.599 180)
			(layer "F.Fab")
			(effects
				(font
					(size 0.7 0.7)
					(thickness 0.15)
				)
				(justify left bottom)
			)
		)
		(fp_text user "License: Apache-2.0"
			(at -0.939 5.799 180)
			(layer "F.Fab")
			(effects
				(font
					(size 0.7 0.7)
					(thickness 0.15)
				)
				(justify left bottom)
			)
		)
		(pad "1" smd roundrect
			(at -0.48 0 180)
			(size 0.59 0.64)
			(layers "F.Cu" "F.Mask" "F.Paste")
			(roundrect_rratio 0.25)
			(net 1 "GND")
			(pintype "passive")
		)
		(pad "2" smd roundrect
			(at 0.48 0 180)
			(size 0.59 0.64)
			(layers "F.Cu" "F.Mask" "F.Paste")
			(roundrect_rratio 0.25)
			(net 45 "/SDI/XTAL1")
			(pintype "passive")
		)
	)
	(footprint "antmicro-footprints:R_0402_1005Metric"
		(layer "F.Cu")
		(at 142.19 103.95 -90)
		(descr "Resistor SMD 0402")
		(tags "resistor SMD 0402")
		(property "Reference" "R31"
			(at -0.01 -1.44 270)
			(layer "F.SilkS")
			(effects
				(font
					(size 0.65 0.65)
					(thickness 0.15)
				)
				(justify left bottom)
			)
		)
		(property "Value" "R_3k01_0402"
			(at 0 1.4 270)
			(layer "F.Fab")
			(hide yes)
			(effects
				(font
					(size 0.7 0.7)
					(thickness 0.15)
				)
				(justify left bottom)
			)
		)
		(property "Datasheet" "https://www.bourns.com/docs/product-datasheets/cr.pdf"
			(at 0 0 270)
			(layer "F.Fab")
			(hide yes)
			(effects
				(font
					(size 1.27 1.27)
					(thickness 0.15)
				)
			)
		)
		(property "Description" "SMD Chip Resistor, 3.01 kohm, ± 1%, 62.5 mW, 0402 [1005 Metric], Thick Film, General Purpose"
			(at 0 0 270)
			(layer "F.Fab")
			(hide yes)
			(effects
				(font
					(size 1.27 1.27)
					(thickness 0.15)
				)
			)
		)
		(property "Author" "Antmicro"
			(at 38.24 246.14 0)
			(layer "F.Fab")
			(hide yes)
			(effects
				(font
					(size 1 1)
					(thickness 0.15)
				)
			)
		)
		(property "License" "Apache-2.0"
			(at 38.24 246.14 0)
			(layer "F.Fab")
			(hide yes)
			(effects
				(font
					(size 1 1)
					(thickness 0.15)
				)
			)
		)
		(property "MPN" "CR0402-FX-3011GLF"
			(at 38.24 246.14 0)
			(layer "F.Fab")
			(hide yes)
			(effects
				(font
					(size 1 1)
					(thickness 0.15)
				)
			)
		)
		(property "Manufacturer" "Bourns"
			(at 38.24 246.14 0)
			(layer "F.Fab")
			(hide yes)
			(effects
				(font
					(size 1 1)
					(thickness 0.15)
				)
			)
		)
		(property "Tolerance" "1%"
			(at 38.24 246.14 0)
			(layer "F.Fab")
			(hide yes)
			(effects
				(font
					(size 1 1)
					(thickness 0.15)
				)
			)
		)
		(property "Val" "3k01"
			(at 38.24 246.14 0)
			(layer "F.Fab")
			(hide yes)
			(effects
				(font
					(size 1 1)
					(thickness 0.15)
				)
			)
		)
		(sheetname "/Power Supply/")
		(sheetfile "supply.kicad_sch")
		(attr smd)
		(fp_rect
			(start -0.925 -0.47)
			(end 0.925 0.47)
			(stroke
				(width 0.05)
				(type default)
			)
			(fill no)
			(layer "F.CrtYd")
		)
		(fp_rect
			(start -0.5 -0.25)
			(end 0.5 0.25)
			(stroke
				(width 0.15)
				(type solid)
			)
			(fill no)
			(layer "F.Fab")
		)
		(fp_text user "License: Apache-2.0"
			(at -0.95 5.169 270)
			(layer "F.Fab")
			(effects
				(font
					(size 0.7 0.7)
					(thickness 0.15)
				)
				(justify left bottom)
			)
		)
		(fp_text user "Author: Antmicro"
			(at -0.95 4.169 270)
			(layer "F.Fab")
			(effects
				(font
					(size 0.7 0.7)
					(thickness 0.15)
				)
				(justify left bottom)
			)
		)
		(fp_text user "${REFERENCE}"
			(at -0.95 3.168 270)
			(layer "F.Fab")
			(effects
				(font
					(size 0.7 0.7)
					(thickness 0.15)
				)
				(justify left bottom)
			)
		)
		(pad "1" smd roundrect
			(at -0.48 0 270)
			(size 0.59 0.64)
			(layers "F.Cu" "F.Mask" "F.Paste")
			(roundrect_rratio 0.25)
			(net 280 "Net-(U8-ADJ)")
			(pintype "passive")
		)
		(pad "2" smd roundrect
			(at 0.48 0 270)
			(size 0.59 0.64)
			(layers "F.Cu" "F.Mask" "F.Paste")
			(roundrect_rratio 0.25)
			(net 272 "Net-(U8-V_{OUT})")
			(pintype "passive")
		)
	)
)
